FILE_TYPE = CONNECTIVITY;
{Allegro Design Entry HDL 16.6-p007 (v16-6-112F) 10/10/2012}
"PAGE_NUMBER" = 125;
0"NC";
1"GND\g";
2"GND\g";
3"GND\g";
4"P3V3_STBY\g";
5"P3V3_STBY\g";
6"P3V3_STBY\g";
7"GND\g";
8"GND\g";
9"P3V3_STBY\g";
10"P3V3_STBY\g";
11"GND\g";
12"P3V3_STBY\g";
13"P3V3_STBY\g";
14"P3V3_STBY\g";
15"P3V3_STBY\g";
16"FM_FLASH_DESC_OVERRIDE";
17"SPI_PCH_IO2";
18"SPI_PCH_IO3";
19"PU_ADR_TIMER_HOLD_OFF_N";
20"RMII_BMC_PCH_SPRNGVLLE_RXER";
21"SPI_PCH_MOSI";
22"FM_USB_P0_EN_BOOT_BIOS_STRAP_N";
23"PU_PCH_TLS_ENABLE_STRAP";
24"FM_UV_ADR_TRIGGER_EN";
25"RMII_PCH_SPRNGVLLE_ARB_OUT";
%"RES"
"2","(1750,3050)","0","mstr_discrete","I11";
;
BOM_COST"SB"
CDS_SEC"1"
$SEC"1"
CDS_LOCATION"R2R11"
ROOM"SB"
CDS_LIB"mstr_discrete"
PART_NUMBER"G21796-026"
LOCATION"R2R11"
VALUE"1.00K"
TOLERANCE"1%"
MATERIAL"EMPTY"
PACK_TYPE"0402"
WATTAGE"1/16W";
"A"
$PN"1"17;
"B"
$PN"2"1;
%"GND"
"1","(1750,2800)","0","mstr_symbols","I14";
;
SIZE"1B"
HDL_POWER"GND"
BOM_COST"SB"
ROOM"SB"
CDS_LIB"mstr_symbols"
VOLTAGE"0.0V"
BODY_TYPE"PLUMBING";
"A\NAC"1;
%"RES"
"2","(1850,1475)","0","mstr_discrete","I15";
;
CDS_SEC"1"
$SEC"1"
BOM_COST"SB"
ROOM"SB"
CDS_LOCATION"R2T1"
CDS_LIB"mstr_discrete"
PART_NUMBER"G21796-026"
LOCATION"R2T1"
VALUE"1.00K"
MATERIAL"CHIP"
PACK_TYPE"0402"
TOLERANCE"1%"
WATTAGE"1/16W";
"A"
$PN"1"18;
"B"
$PN"2"2;
%"GND"
"1","(1850,1225)","0","mstr_symbols","I16";
;
HDL_POWER"GND"
BOM_COST"SB"
ROOM"SB"
VOLTAGE"0.0V"
CDS_LIB"mstr_symbols"
SIZE"1B"
BODY_TYPE"PLUMBING";
"A\NAC"2;
%"RES"
"2","(-950,3150)","0","mstr_discrete","I21";
;
CDS_SEC"1"
SEC_TYPE"0402"
SEC"1"
BOM_COST"SB"
ROOM"SB"
CDS_LOCATION"R8E6"
CDS_LIB"mstr_discrete"
PART_NUMBER"G21796-026"
MATERIAL"EMPTY"
VALUE"1.00K"
WATTAGE"1/16W"
LOCATION"R8E6"
TOLERANCE"1%"
PACK_TYPE"0402";
"A"
$PN"1"4;
"B"
$PN"2"21;
%"RES"
"2","(-950,2750)","0","mstr_discrete","I24";
;
$SEC"1"
CDS_SEC"1"
BOM_COST"SB"
ROOM"SB"
CDS_LOCATION"R8E4"
CDS_LIB"mstr_discrete"
MATERIAL"EMPTY"
PART_NUMBER"G21796-026"
VALUE"1.00K"
WATTAGE"1/16W"
LOCATION"R8E4"
TOLERANCE"1%"
PACK_TYPE"0402";
"A"
$PN"1"21;
"B"
$PN"2"3;
%"GND"
"1","(-950,2500)","0","mstr_symbols","I25";
;
HDL_POWER"GND"
ROOM"SB"
BOM_COST"SB"
VOLTAGE"0.0V"
SIZE"1B"
CDS_LIB"mstr_symbols"
BODY_TYPE"PLUMBING";
"A\NAC"3;
%"RES"
"2","(-3225,2525)","0","mstr_discrete","I40";
;
CDS_SEC"1"
BOM_COST"SB"
$SEC"1"
CDS_LOCATION"R8C18"
ROOM"SB"
CDS_LIB"mstr_discrete"
LOCATION"R8C18"
PART_NUMBER"G21796-026"
VALUE"1.00K"
PACK_TYPE"0402"
MATERIAL"CHIP"
WATTAGE"1/16W"
TOLERANCE"1%";
"A"
$PN"1"5;
"B"
$PN"2"23;
%"RES"
"2","(-3225,2200)","0","mstr_discrete","I41";
;
CDS_SEC"1"
ROOM"SB"
SEC"1"
BOM_COST"SB"
SEC_TYPE"0402"
CDS_LOCATION"R8C17"
CDS_LIB"mstr_discrete"
PACK_TYPE"0402"
MATERIAL"EMPTY"
LOCATION"R8C17"
VALUE"1.00K"
WATTAGE"1/16W"
TOLERANCE"1%"
PART_NUMBER"G21796-026";
"A"
$PN"1"23;
"B"
$PN"2"8;
%"P3V3_STBY"
"1","(-950,3375)","0","mstr_symbols","I48";
;
VOLTAGE"3.3V"
CDS_LIB"mstr_symbols"
SIZE"1B"
BODY_TYPE"PLUMBING"
HDL_POWER"P3V3_STBY";
"G\NAC"4;
%"P3V3_STBY"
"1","(-3225,2750)","0","mstr_symbols","I49";
;
SIZE"1B"
BODY_TYPE"PLUMBING"
CDS_LIB"mstr_symbols"
VOLTAGE"3.3V"
HDL_POWER"P3V3_STBY";
"G\NAC"5;
%"RES"
"2","(-925,4450)","0","mstr_discrete","I50";
;
ROOM"SB"
$SEC"1"
CDS_SEC"1"
BOM_COST"SB"
CDS_LOCATION"R8D5"
CDS_LIB"mstr_discrete"
MATERIAL"EMPTY"
LOCATION"R8D5"
PART_NUMBER"G21796-026"
VALUE"1.00K"
WATTAGE"1/16W"
TOLERANCE"1%"
PACK_TYPE"0402";
"A"
$PN"1"19;
"B"
$PN"2"7;
%"P3V3_STBY"
"1","(-925,5100)","0","mstr_symbols","I51";
;
SIZE"1B"
CDS_LIB"mstr_symbols"
VOLTAGE"3.3V"
BODY_TYPE"PLUMBING"
HDL_POWER"P3V3_STBY";
"G\NAC"6;
%"RES"
"2","(-925,4925)","0","mstr_discrete","I52";
;
CDS_SEC"1"
$SEC"1"
BOM_COST"SB"
ROOM"SB_HEADERS"
CDS_LOCATION"R8D13"
CDS_LIB"mstr_discrete"
LOCATION"R8D13"
PART_NUMBER"G21796-016"
VALUE"10.0K"
PACK_TYPE"0402"
MATERIAL"CHIP"
WATTAGE"1/16W"
TOLERANCE"1%";
"A"
$PN"1"6;
"B"
$PN"2"19;
%"GND"
"1","(-925,4200)","0","mstr_symbols","I54";
;
HDL_POWER"GND"
SIZE"1B"
ROOM"SB"
BOM_COST"SB"
CDS_LIB"mstr_symbols"
BODY_TYPE"PLUMBING"
VOLTAGE"0.0V";
"A\NAC"7;
%"GND"
"1","(-3225,2000)","0","mstr_symbols","I6";
;
BOM_COST"SB"
ROOM"SB"
HDL_POWER"GND"
VOLTAGE"0.0V"
CDS_LIB"mstr_symbols"
SIZE"1B"
BODY_TYPE"PLUMBING";
"A\NAC"8;
%"RES"
"2","(-3275,4975)","0","mstr_discrete","I60";
;
ROOM"SB"
$SEC"1"
CDS_SEC"1"
BOM_COST"SB"
CDS_LOCATION"R7D13"
CDS_LIB"mstr_discrete"
PART_NUMBER"G21796-345"
LOCATION"R7D13"
MATERIAL"EMPTY"
VALUE"8.2K"
TOLERANCE"1%"
WATTAGE"1/16W"
PACK_TYPE"0402";
"A"
$PN"1"9;
"B"
$PN"2"20;
%"P3V3_STBY"
"1","(-3275,5200)","0","mstr_symbols","I61";
;
BODY_TYPE"PLUMBING"
CDS_LIB"mstr_symbols"
SIZE"1B"
VOLTAGE"3.3V"
HDL_POWER"P3V3_STBY";
"G\NAC"9;
%"P3V3_STBY"
"1","(-5050,3975)","0","mstr_symbols","I66";
;
CDS_LIB"mstr_symbols"
SIZE"1B"
VOLTAGE"3.3V"
BODY_TYPE"PLUMBING"
HDL_POWER"P3V3_STBY";
"G\NAC"10;
%"GND"
"1","(-5050,3175)","0","mstr_symbols","I69";
;
HDL_POWER"GND"
SIZE"1B"
ROOM"SB"
BOM_COST"SB"
CDS_LIB"mstr_symbols"
BODY_TYPE"PLUMBING"
VOLTAGE"0.0V";
"A\NAC"11;
%"RES"
"2","(-5050,3375)","0","mstr_discrete","I70";
;
CDS_SEC"1"
SEC"1"
SEC_TYPE"0402"
BOM_COST"SB"
ROOM"SB"
CDS_LOCATION"R7D1"
CDS_LIB"mstr_discrete"
PART_NUMBER"G21796-026"
VALUE"1.00K"
WATTAGE"1/16W"
TOLERANCE"1%"
LOCATION"R7D1"
MATERIAL"CHIP"
PACK_TYPE"0402";
"A"
$PN"1"25;
"B"
$PN"2"11;
%"RES"
"2","(-5050,3750)","0","mstr_discrete","I71";
;
CDS_SEC"1"
SEC_TYPE"0402"
SEC"1"
BOM_COST"SB"
ROOM"SB"
CDS_LOCATION"R8D16"
CDS_LIB"mstr_discrete"
LOCATION"R8D16"
PART_NUMBER"G21796-016"
VALUE"10.0K"
MATERIAL"EMPTY"
TOLERANCE"1%"
WATTAGE"1/16W"
PACK_TYPE"0402";
"A"
$PN"1"10;
"B"
$PN"2"25;
%"RES"
"2","(400,4600)","0","mstr_discrete","I72";
;
CDS_SEC"1"
SEC_TYPE"0402"
SEC"1"
CDS_LOCATION"R3N2"
BOM_COST"SB"
ROOM"BMC_MISC"
CDS_LIB"mstr_discrete"
MATERIAL"EMPTY"
LOCATION"R3N2"
PART_NUMBER"G21796-072"
VALUE"4.75K"
PACK_TYPE"0402"
WATTAGE"1/16W"
TOLERANCE"1%";
"A"
$PN"1"12;
"B"
$PN"2"16;
%"P3V3_STBY"
"1","(400,4900)","0","mstr_symbols","I74";
;
SIZE"1B"
CDS_LIB"mstr_symbols"
VOLTAGE"3.3V"
BODY_TYPE"PLUMBING"
HDL_POWER"P3V3_STBY";
"G\NAC"12;
%"P3V3_STBY"
"1","(-3350,1600)","0","mstr_symbols","I75";
;
SIZE"1B"
BODY_TYPE"PLUMBING"
CDS_LIB"mstr_symbols"
VOLTAGE"3.3V"
HDL_POWER"P3V3_STBY";
"G\NAC"13;
%"RES"
"2","(-3350,1375)","0","mstr_discrete","I76";
;
ROOM"ADR"
$SEC"1"
CDS_SEC"1"
CDS_LOCATION"R2U30"
CDS_LIB"mstr_discrete"
PART_NUMBER"G21796-072"
MATERIAL"CHIP"
WATTAGE"1/16W"
VALUE"4.75K"
LOCATION"R2U30"
PACK_TYPE"0402"
TOLERANCE"1%";
"A"
$PN"1"13;
"B"
$PN"2"24;
%"RES"
"2","(1850,1875)","0","mstr_discrete","I78";
;
CDS_SEC"1"
ROOM"SB"
SEC"1"
SEC_TYPE"0402"
BOM_COST"SB"
CDS_LOCATION"R3N17"
CDS_LIB"mstr_discrete"
PART_NUMBER"G21796-026"
MATERIAL"EMPTY"
LOCATION"R3N17"
VALUE"1.00K"
TOLERANCE"1%"
WATTAGE"1/16W"
PACK_TYPE"0402";
"A"
$PN"1"14;
"B"
$PN"2"18;
%"P3V3_STBY"
"1","(1850,2125)","0","mstr_symbols","I79";
;
BODY_TYPE"PLUMBING"
CDS_LIB"mstr_symbols"
SIZE"1B"
VOLTAGE"3.3V"
HDL_POWER"P3V3_STBY";
"G\NAC"14;
%"RES"
"2","(-925,1525)","0","mstr_discrete","I83";
;
CDS_SEC"1"
SEC_TYPE"0402"
ROOM"SB"
SEC"1"
BOM_COST"SB"
CDS_LOCATION"R2N14"
CDS_LIB"mstr_discrete"
LOCATION"R2N14"
VALUE"1.00K"
TOLERANCE"1%"
MATERIAL"EMPTY"
PART_NUMBER"G21796-026"
WATTAGE"1/16W"
PACK_TYPE"0402";
"A"
$PN"1"15;
"B"
$PN"2"22;
%"P3V3_STBY"
"1","(-925,1750)","0","mstr_symbols","I84";
;
SIZE"1B"
VOLTAGE"3.3V"
CDS_LIB"mstr_symbols"
BODY_TYPE"PLUMBING"
HDL_POWER"P3V3_STBY";
"G\NAC"15;
END.
